# S9S_MB_2U (Grand Teton) — schematic netlist excerpt (pin names and nets, part order shuffled) for the footprints in the layout excerpt that follows; sources: Cadence DE-HDL packaged netlist, KiCad conversion of 03242023_DA0F0TMBIJ0_F0T_Motherboard_J_brd_V01_OCP.brd

PR4238  Q_RES  0 5% EMPTY  pkg 0402LF  page 284 : A = PVCCFA_EHV_FIVRA_CPU1_IMON4 ; B = GND
R1463  Q_RES  0 5% CHIP  pkg 0402LF  page 189 : A = P1V05_PCH_AUX ; B = P1V05_PCH_PLL_AUX

(kicad_pcb
	(version 20260206)
	(generator "pcbnew")
	(generator_version "10.0")
	(general
		(thickness 1.6)
		(legacy_teardrops no)
	)
	(paper "A4")
	(title_block
		(title "03242023_DA0F0TMBIJ0_F0T_Motherboard_J_brd_V01_OCP.brd")
		(comment 1 "Grand Teton / footprints 4360-4361 of 6105")
	)
	(layers
		(0 "F.Cu" signal "TOP")
		(4 "In1.Cu" signal "GND")
		(6 "In2.Cu" signal "IN1")
		(8 "In3.Cu" signal "GND1")
		(10 "In4.Cu" signal "IN2")
		(12 "In5.Cu" signal "GND2")
		(14 "In6.Cu" signal "IN3")
		(16 "In7.Cu" signal "GND3")
		(18 "In8.Cu" signal "VCC")
		(20 "In9.Cu" signal "VCC1")
		(22 "In10.Cu" signal "GND4")
		(24 "In11.Cu" signal "IN4")
		(26 "In12.Cu" signal "GND5")
		(28 "In13.Cu" signal "IN5")
		(30 "In14.Cu" signal "GND6")
		(32 "In15.Cu" signal "IN6")
		(34 "In16.Cu" signal "GND7")
		(2 "B.Cu" signal "BOTTOM")
		(9 "F.Adhes" user "F.Adhesive")
		(11 "B.Adhes" user "B.Adhesive")
		(13 "F.Paste" user "Package Geometry/Pastemask Top")
		(15 "B.Paste" user "Package Geometry/Pastemask Bottom")
		(5 "F.SilkS" user "Ref Des/Silkscreen Top")
		(7 "B.SilkS" user "Ref Des/Silkscreen Bottom")
		(1 "F.Mask" user "Board Geometry/Soldermask Top")
		(3 "B.Mask" user "Board Geometry/Soldermask Bottom")
		(17 "Dwgs.User" user "User.Drawings")
		(19 "Cmts.User" user "User.Comments")
		(21 "Eco1.User" user "User.Eco1")
		(23 "Eco2.User" user "User.Eco2")
		(25 "Edge.Cuts" user "Board Geometry/Outline")
		(27 "Margin" user)
		(31 "F.CrtYd" user "Package Geometry/Place Bound Top")
		(29 "B.CrtYd" user "Package Geometry/Place Bound Bottom")
		(35 "F.Fab" user "Ref Des/Assembly Top")
		(33 "B.Fab" user "Ref Des/Assembly Bottom")
	)
	(footprint ""
		(layer "B.Cu")
		(at 339.12048 -53.471826 90)
		(property "Reference" "R1463"
			(at 0 0 90)
			(layer "B.SilkS")
			(hide yes)
			(effects
				(font
					(size 1.27 1.27)
				)
				(justify mirror)
			)
		)
		(property "Value" ""
			(at 0 0 90)
			(layer "B.Fab")
			(effects
				(font
					(size 1.27 1.27)
				)
				(justify mirror)
			)
		)
		(duplicate_pad_numbers_are_jumpers no)
		(fp_line
			(start 0.7874 -0.4064)
			(end -0.7874 -0.4064)
			(stroke
				(width 0.1524)
				(type default)
			)
			(layer "B.SilkS")
		)
		(fp_line
			(start -0.7874 -0.4064)
			(end -0.7874 0.4064)
			(stroke
				(width 0.1524)
				(type default)
			)
			(layer "B.SilkS")
		)
		(fp_line
			(start 0.7874 0.4064)
			(end 0.7874 -0.4064)
			(stroke
				(width 0.1524)
				(type default)
			)
			(layer "B.SilkS")
		)
		(fp_line
			(start -0.7874 0.4064)
			(end 0.7874 0.4064)
			(stroke
				(width 0.1524)
				(type default)
			)
			(layer "B.SilkS")
		)
		(fp_line
			(start 0.67945 -0.305054)
			(end 0.12065 -0.305054)
			(stroke
				(width 0.1)
				(type default)
			)
			(layer "B.Fab")
		)
		(fp_line
			(start 0.12065 -0.305054)
			(end 0.12065 -0.2794)
			(stroke
				(width 0.1)
				(type default)
			)
			(layer "B.Fab")
		)
		(fp_line
			(start -0.12065 -0.3048)
			(end -0.67945 -0.3048)
			(stroke
				(width 0.1)
				(type default)
			)
			(layer "B.Fab")
		)
		(fp_line
			(start -0.67945 -0.3048)
			(end -0.67945 0.3048)
			(stroke
				(width 0.1)
				(type default)
			)
			(layer "B.Fab")
		)
		(fp_line
			(start 0.12065 -0.2794)
			(end -0.12065 -0.2794)
			(stroke
				(width 0.1)
				(type default)
			)
			(layer "B.Fab")
		)
		(fp_line
			(start -0.12065 -0.2794)
			(end -0.12065 -0.3048)
			(stroke
				(width 0.1)
				(type default)
			)
			(layer "B.Fab")
		)
		(fp_line
			(start 0.12065 0.2794)
			(end 0.12065 0.3048)
			(stroke
				(width 0.1)
				(type default)
			)
			(layer "B.Fab")
		)
		(fp_line
			(start -0.120396 0.2794)
			(end 0.12065 0.2794)
			(stroke
				(width 0.1)
				(type default)
			)
			(layer "B.Fab")
		)
		(fp_line
			(start 0.67945 0.3048)
			(end 0.67945 -0.305054)
			(stroke
				(width 0.1)
				(type default)
			)
			(layer "B.Fab")
		)
		(fp_line
			(start 0.12065 0.3048)
			(end 0.67945 0.3048)
			(stroke
				(width 0.1)
				(type default)
			)
			(layer "B.Fab")
		)
		(fp_line
			(start -0.120396 0.3048)
			(end -0.120396 0.2794)
			(stroke
				(width 0.1)
				(type default)
			)
			(layer "B.Fab")
		)
		(fp_line
			(start -0.67945 0.3048)
			(end -0.120396 0.3048)
			(stroke
				(width 0.1)
				(type default)
			)
			(layer "B.Fab")
		)
		(pad "1" smd circle
			(at 0.40005 0 270)
			(size 0 0)
			(layers "B.Cu" "B.Mask" "B.Paste")
			(net "P1V05_PCH_AUX")
		)
		(pad "2" smd circle
			(at -0.40005 0 270)
			(size 0 0)
			(layers "B.Cu" "B.Mask" "B.Paste")
			(net "P1V05_PCH_PLL_AUX")
		)
	)
	(footprint ""
		(layer "B.Cu")
		(at 107.77728 -356.504748 -90)
		(property "Reference" "PR4238"
			(at 0 0 90)
			(layer "B.SilkS")
			(hide yes)
			(effects
				(font
					(size 1.27 1.27)
				)
				(justify mirror)
			)
		)
		(property "Value" ""
			(at 0 0 90)
			(layer "B.Fab")
			(effects
				(font
					(size 1.27 1.27)
				)
				(justify mirror)
			)
		)
		(duplicate_pad_numbers_are_jumpers no)
		(fp_line
			(start -0.7874 0.4064)
			(end 0.7874 0.4064)
			(stroke
				(width 0.1524)
				(type default)
			)
			(layer "B.SilkS")
		)
		(fp_line
			(start 0.7874 0.4064)
			(end 0.7874 -0.4064)
			(stroke
				(width 0.1524)
				(type default)
			)
			(layer "B.SilkS")
		)
		(fp_line
			(start -0.7874 -0.4064)
			(end -0.7874 0.4064)
			(stroke
				(width 0.1524)
				(type default)
			)
			(layer "B.SilkS")
		)
		(fp_line
			(start 0.7874 -0.4064)
			(end -0.7874 -0.4064)
			(stroke
				(width 0.1524)
				(type default)
			)
			(layer "B.SilkS")
		)
		(fp_line
			(start -0.67945 0.3048)
			(end -0.120396 0.3048)
			(stroke
				(width 0.1)
				(type default)
			)
			(layer "B.Fab")
		)
		(fp_line
			(start -0.120396 0.3048)
			(end -0.120396 0.2794)
			(stroke
				(width 0.1)
				(type default)
			)
			(layer "B.Fab")
		)
		(fp_line
			(start 0.12065 0.3048)
			(end 0.67945 0.3048)
			(stroke
				(width 0.1)
				(type default)
			)
			(layer "B.Fab")
		)
		(fp_line
			(start 0.67945 0.3048)
			(end 0.67945 -0.305054)
			(stroke
				(width 0.1)
				(type default)
			)
			(layer "B.Fab")
		)
		(fp_line
			(start -0.120396 0.2794)
			(end 0.12065 0.2794)
			(stroke
				(width 0.1)
				(type default)
			)
			(layer "B.Fab")
		)
		(fp_line
			(start 0.12065 0.2794)
			(end 0.12065 0.3048)
			(stroke
				(width 0.1)
				(type default)
			)
			(layer "B.Fab")
		)
		(fp_line
			(start -0.12065 -0.2794)
			(end -0.12065 -0.3048)
			(stroke
				(width 0.1)
				(type default)
			)
			(layer "B.Fab")
		)
		(fp_line
			(start 0.12065 -0.2794)
			(end -0.12065 -0.2794)
			(stroke
				(width 0.1)
				(type default)
			)
			(layer "B.Fab")
		)
		(fp_line
			(start -0.67945 -0.3048)
			(end -0.67945 0.3048)
			(stroke
				(width 0.1)
				(type default)
			)
			(layer "B.Fab")
		)
		(fp_line
			(start -0.12065 -0.3048)
			(end -0.67945 -0.3048)
			(stroke
				(width 0.1)
				(type default)
			)
			(layer "B.Fab")
		)
		(fp_line
			(start 0.12065 -0.305054)
			(end 0.12065 -0.2794)
			(stroke
				(width 0.1)
				(type default)
			)
			(layer "B.Fab")
		)
		(fp_line
			(start 0.67945 -0.305054)
			(end 0.12065 -0.305054)
			(stroke
				(width 0.1)
				(type default)
			)
			(layer "B.Fab")
		)
		(pad "1" smd circle
			(at 0.40005 0 90)
			(size 0 0)
			(layers "B.Cu" "B.Mask" "B.Paste")
			(net "PVCCFA_EHV_FIVRA_CPU1_IMON4")
		)
		(pad "2" smd circle
			(at -0.40005 0 90)
			(size 0 0)
			(layers "B.Cu" "B.Mask" "B.Paste")
			(net "GND")
		)
	)
)
